(kicad_pcb
	(version 20241229)
	(generator "pcbnew")
	(generator_version "9.0")
	(general
		(thickness 1.292)
		(legacy_teardrops no)
	)
	(paper "A4")
	(title_block
		(title "LPDDR5 Testbed")
		(date "2023-12-19")
		(rev "1.0.0")
		(comment 9 "footprints 121-127 of 160")
	)
	(layers
		(0 "F.Cu" signal)
		(4 "In1.Cu" power)
		(6 "In2.Cu" power)
		(8 "In3.Cu" signal)
		(10 "In4.Cu" signal)
		(2 "B.Cu" signal)
		(9 "F.Adhes" user "F.Adhesive")
		(11 "B.Adhes" user "B.Adhesive")
		(13 "F.Paste" user)
		(15 "B.Paste" user)
		(5 "F.SilkS" user "F.Silkscreen")
		(7 "B.SilkS" user "B.Silkscreen")
		(1 "F.Mask" user)
		(3 "B.Mask" user)
		(17 "Dwgs.User" user "User.Drawings")
		(19 "Cmts.User" user "User.Comments")
		(21 "Eco1.User" user "User.Eco1")
		(23 "Eco2.User" user "User.Eco2")
		(25 "Edge.Cuts" user)
		(27 "Margin" user)
		(31 "F.CrtYd" user "F.Courtyard")
		(29 "B.CrtYd" user "B.Courtyard")
		(35 "F.Fab" user)
		(33 "B.Fab" user)
	)
	(footprint "antmicro-footprints:D_SOD-123F"
		(layer "B.Cu")
		(at 113.1 64)
		(property "Reference" "D1"
			(at -2 -1.3 0)
			(unlocked yes)
			(layer "B.SilkS")
			(effects
				(font
					(size 0.7 0.7)
					(thickness 0.15)
				)
				(justify right bottom mirror)
			)
		)
		(property "Value" "PTVS48VS1UR"
			(at 0 -2.1 0)
			(layer "B.Fab")
			(effects
				(font
					(size 0.7 0.7)
					(thickness 0.15)
				)
				(justify right bottom mirror)
			)
		)
		(property "Author" "Antmicro"
			(at 0 0 0)
			(layer "B.Fab")
			(hide yes)
			(effects
				(font
					(size 1 1)
					(thickness 0.15)
				)
				(justify mirror)
			)
		)
		(property "License" "Apache-2.0"
			(at 0 0 0)
			(layer "B.Fab")
			(hide yes)
			(effects
				(font
					(size 1 1)
					(thickness 0.15)
				)
				(justify mirror)
			)
		)
		(property "MPN" "PTVS48VS1UR,115"
			(at 0 0 0)
			(layer "B.Fab")
			(hide yes)
			(effects
				(font
					(size 1 1)
					(thickness 0.15)
				)
				(justify mirror)
			)
		)
		(property "Manufacturer" "Nexperia"
			(at 0 0 0)
			(layer "B.Fab")
			(hide yes)
			(effects
				(font
					(size 1 1)
					(thickness 0.15)
				)
				(justify mirror)
			)
		)
		(sheetname "Power supply")
		(sheetfile "power_supply.kicad_sch")
		(attr smd)
		(fp_line
			(start -0.7 0.8)
			(end -0.7 -0.8)
			(stroke
				(width 0.15)
				(type solid)
			)
			(layer "B.SilkS")
		)
		(fp_line
			(start -2.21 -1.1)
			(end -2.21 1.1)
			(stroke
				(width 0.05)
				(type solid)
			)
			(layer "B.CrtYd")
		)
		(fp_line
			(start 2.2 -1.1)
			(end -2.21 -1.1)
			(stroke
				(width 0.05)
				(type solid)
			)
			(layer "B.CrtYd")
		)
		(fp_line
			(start 2.2 1.1)
			(end -2.21 1.1)
			(stroke
				(width 0.05)
				(type solid)
			)
			(layer "B.CrtYd")
		)
		(fp_line
			(start 2.2 1.1)
			(end 2.2 -1.1)
			(stroke
				(width 0.05)
				(type solid)
			)
			(layer "B.CrtYd")
		)
		(fp_line
			(start -0.8 0.8)
			(end -0.8 -0.8)
			(stroke
				(width 0.1)
				(type solid)
			)
			(layer "B.Fab")
		)
		(fp_rect
			(start -1.75 0.802)
			(end 1.749 -0.8)
			(stroke
				(width 0.1)
				(type solid)
			)
			(fill no)
			(layer "B.Fab")
		)
		(pad "A" smd roundrect
			(at 1.398 0)
			(size 1.2 1.2)
			(layers "B.Cu" "B.Mask" "B.Paste")
			(roundrect_rratio 0.25)
			(net 15 "/Power supply/3.3V_QWIIC")
			(pinfunction "A")
			(pintype "passive")
		)
		(pad "K" smd roundrect
			(at -1.401 0)
			(size 1.2 1.2)
			(layers "B.Cu" "B.Mask" "B.Paste")
			(roundrect_rratio 0.25)
			(net 5 "+5V")
			(pinfunction "C")
			(pintype "passive")
		)
	)
	(footprint "antmicro-footprints:R_0402_1005Metric"
		(layer "B.Cu")
		(at 136.65 93.85 -90)
		(descr "Resistor SMD 0402")
		(tags "resistor SMD 0402")
		(property "Reference" "R84"
			(at 0.85 -0.35 90)
			(unlocked yes)
			(layer "B.SilkS")
			(effects
				(font
					(size 0.7 0.7)
					(thickness 0.15)
				)
				(justify left bottom mirror)
			)
		)
		(property "Value" "R_100R_0402"
			(at -1.011843 -1.772047 90)
			(layer "B.Fab")
			(effects
				(font
					(size 0.7 0.7)
					(thickness 0.15)
				)
				(justify left bottom mirror)
			)
		)
		(property "Author" "Antmicro"
			(at 42.8 230.5 0)
			(layer "B.Fab")
			(hide yes)
			(effects
				(font
					(size 1 1)
					(thickness 0.15)
				)
				(justify mirror)
			)
		)
		(property "License" "Apache-2.0"
			(at 42.8 230.5 0)
			(layer "B.Fab")
			(hide yes)
			(effects
				(font
					(size 1 1)
					(thickness 0.15)
				)
				(justify mirror)
			)
		)
		(property "MPN" "CR0402-FX-1000GLF"
			(at 42.8 230.5 0)
			(layer "B.Fab")
			(hide yes)
			(effects
				(font
					(size 1 1)
					(thickness 0.15)
				)
				(justify mirror)
			)
		)
		(property "Manufacturer" "Bourns"
			(at 42.8 230.5 0)
			(layer "B.Fab")
			(hide yes)
			(effects
				(font
					(size 1 1)
					(thickness 0.15)
				)
				(justify mirror)
			)
		)
		(property "Tolerance" "1%"
			(at 42.8 230.5 0)
			(layer "B.Fab")
			(hide yes)
			(effects
				(font
					(size 1 1)
					(thickness 0.15)
				)
				(justify mirror)
			)
		)
		(property "Val" "100R"
			(at 42.8 230.5 0)
			(layer "B.Fab")
			(hide yes)
			(effects
				(font
					(size 1 1)
					(thickness 0.15)
				)
				(justify mirror)
			)
		)
		(sheetname "Translators1")
		(sheetfile "translators.kicad_sch")
		(attr smd)
		(fp_rect
			(start -0.93 0.47)
			(end 0.93 -0.47)
			(stroke
				(width 0.05)
				(type solid)
			)
			(fill no)
			(layer "B.CrtYd")
		)
		(fp_rect
			(start -0.5 0.25)
			(end 0.5 -0.25)
			(stroke
				(width 0.15)
				(type solid)
			)
			(fill no)
			(layer "B.Fab")
		)
		(pad "1" smd roundrect
			(at -0.485 0 270)
			(size 0.59 0.64)
			(layers "B.Cu" "B.Mask" "B.Paste")
			(roundrect_rratio 0.25)
			(net 112 "/LPDDR5/LPDDR5_B.CK_P")
			(pintype "passive")
		)
		(pad "2" smd roundrect
			(at 0.485 0 270)
			(size 0.59 0.64)
			(layers "B.Cu" "B.Mask" "B.Paste")
			(roundrect_rratio 0.25)
			(net 14 "GND")
			(pintype "passive")
		)
	)
	(footprint "antmicro-footprints:R_0402_1005Metric"
		(layer "B.Cu")
		(at 163.5 89.465 180)
		(descr "Resistor SMD 0402")
		(tags "resistor SMD 0402")
		(property "Reference" "R79"
			(at -0.9 0.765 0)
			(unlocked yes)
			(layer "B.SilkS")
			(effects
				(font
					(size 0.7 0.7)
					(thickness 0.15)
				)
				(justify left bottom mirror)
			)
		)
		(property "Value" "R_100R_0402"
			(at -1.011843 -1.772047 0)
			(layer "B.Fab")
			(effects
				(font
					(size 0.7 0.7)
					(thickness 0.15)
				)
				(justify left bottom mirror)
			)
		)
		(property "Author" "Antmicro"
			(at 327 178.93 0)
			(layer "B.Fab")
			(hide yes)
			(effects
				(font
					(size 1 1)
					(thickness 0.15)
				)
				(justify mirror)
			)
		)
		(property "License" "Apache-2.0"
			(at 327 178.93 0)
			(layer "B.Fab")
			(hide yes)
			(effects
				(font
					(size 1 1)
					(thickness 0.15)
				)
				(justify mirror)
			)
		)
		(property "MPN" "CR0402-FX-1000GLF"
			(at 327 178.93 0)
			(layer "B.Fab")
			(hide yes)
			(effects
				(font
					(size 1 1)
					(thickness 0.15)
				)
				(justify mirror)
			)
		)
		(property "Manufacturer" "Bourns"
			(at 327 178.93 0)
			(layer "B.Fab")
			(hide yes)
			(effects
				(font
					(size 1 1)
					(thickness 0.15)
				)
				(justify mirror)
			)
		)
		(property "Tolerance" "1%"
			(at 327 178.93 0)
			(layer "B.Fab")
			(hide yes)
			(effects
				(font
					(size 1 1)
					(thickness 0.15)
				)
				(justify mirror)
			)
		)
		(property "Val" "100R"
			(at 327 178.93 0)
			(layer "B.Fab")
			(hide yes)
			(effects
				(font
					(size 1 1)
					(thickness 0.15)
				)
				(justify mirror)
			)
		)
		(sheetname "Translators1")
		(sheetfile "translators.kicad_sch")
		(attr smd)
		(fp_rect
			(start -0.93 0.47)
			(end 0.93 -0.47)
			(stroke
				(width 0.05)
				(type solid)
			)
			(fill no)
			(layer "B.CrtYd")
		)
		(fp_rect
			(start -0.5 0.25)
			(end 0.5 -0.25)
			(stroke
				(width 0.15)
				(type solid)
			)
			(fill no)
			(layer "B.Fab")
		)
		(pad "1" smd roundrect
			(at -0.485 0 180)
			(size 0.59 0.64)
			(layers "B.Cu" "B.Mask" "B.Paste")
			(roundrect_rratio 0.25)
			(net 109 "/LPDDR5/LPDDR5_B.WCK0_N")
			(pintype "passive")
		)
		(pad "2" smd roundrect
			(at 0.485 0 180)
			(size 0.59 0.64)
			(layers "B.Cu" "B.Mask" "B.Paste")
			(roundrect_rratio 0.25)
			(net 14 "GND")
			(pintype "passive")
		)
	)
	(footprint "antmicro-footprints:R_0402_1005Metric"
		(layer "B.Cu")
		(at 106.18 89.57 180)
		(descr "Resistor SMD 0402")
		(tags "resistor SMD 0402")
		(property "Reference" "R49"
			(at -1.02 0.67 0)
			(unlocked yes)
			(layer "B.SilkS")
			(effects
				(font
					(size 0.7 0.7)
					(thickness 0.15)
				)
				(justify left bottom mirror)
			)
		)
		(property "Value" "R_100R_0402"
			(at -1.011843 -1.772047 0)
			(layer "B.Fab")
			(effects
				(font
					(size 0.7 0.7)
					(thickness 0.15)
				)
				(justify left bottom mirror)
			)
		)
		(property "Author" "Antmicro"
			(at 212.36 179.14 0)
			(layer "B.Fab")
			(hide yes)
			(effects
				(font
					(size 1 1)
					(thickness 0.15)
				)
				(justify mirror)
			)
		)
		(property "License" "Apache-2.0"
			(at 212.36 179.14 0)
			(layer "B.Fab")
			(hide yes)
			(effects
				(font
					(size 1 1)
					(thickness 0.15)
				)
				(justify mirror)
			)
		)
		(property "MPN" "CR0402-FX-1000GLF"
			(at 212.36 179.14 0)
			(layer "B.Fab")
			(hide yes)
			(effects
				(font
					(size 1 1)
					(thickness 0.15)
				)
				(justify mirror)
			)
		)
		(property "Manufacturer" "Bourns"
			(at 212.36 179.14 0)
			(layer "B.Fab")
			(hide yes)
			(effects
				(font
					(size 1 1)
					(thickness 0.15)
				)
				(justify mirror)
			)
		)
		(property "Tolerance" "1%"
			(at 212.36 179.14 0)
			(layer "B.Fab")
			(hide yes)
			(effects
				(font
					(size 1 1)
					(thickness 0.15)
				)
				(justify mirror)
			)
		)
		(property "Val" "100R"
			(at 212.36 179.14 0)
			(layer "B.Fab")
			(hide yes)
			(effects
				(font
					(size 1 1)
					(thickness 0.15)
				)
				(justify mirror)
			)
		)
		(sheetname "Translators")
		(sheetfile "translators.kicad_sch")
		(attr smd)
		(fp_rect
			(start -0.93 0.47)
			(end 0.93 -0.47)
			(stroke
				(width 0.05)
				(type solid)
			)
			(fill no)
			(layer "B.CrtYd")
		)
		(fp_rect
			(start -0.5 0.25)
			(end 0.5 -0.25)
			(stroke
				(width 0.15)
				(type solid)
			)
			(fill no)
			(layer "B.Fab")
		)
		(pad "1" smd roundrect
			(at -0.485 0 180)
			(size 0.59 0.64)
			(layers "B.Cu" "B.Mask" "B.Paste")
			(roundrect_rratio 0.25)
			(net 47 "/LPDDR5/LPDDR5_A.WCK1_N")
			(pintype "passive")
		)
		(pad "2" smd roundrect
			(at 0.485 0 180)
			(size 0.59 0.64)
			(layers "B.Cu" "B.Mask" "B.Paste")
			(roundrect_rratio 0.25)
			(net 14 "GND")
			(pintype "passive")
		)
	)
	(footprint "antmicro-footprints:R_0402_1005Metric"
		(layer "B.Cu")
		(at 146.05 93.8 90)
		(descr "Resistor SMD 0402")
		(tags "resistor SMD 0402")
		(property "Reference" "R2"
			(at -0.7 1.55 90)
			(unlocked yes)
			(layer "B.SilkS")
			(effects
				(font
					(size 0.7 0.7)
					(thickness 0.15)
				)
				(justify right bottom mirror)
			)
		)
		(property "Value" "R_100R_0402"
			(at -1.011843 -1.772047 90)
			(layer "B.Fab")
			(effects
				(font
					(size 0.7 0.7)
					(thickness 0.15)
				)
				(justify right bottom mirror)
			)
		)
		(property "Author" "Antmicro"
			(at 239.85 -52.25 0)
			(layer "B.Fab")
			(hide yes)
			(effects
				(font
					(size 1 1)
					(thickness 0.15)
				)
				(justify mirror)
			)
		)
		(property "License" "Apache-2.0"
			(at 239.85 -52.25 0)
			(layer "B.Fab")
			(hide yes)
			(effects
				(font
					(size 1 1)
					(thickness 0.15)
				)
				(justify mirror)
			)
		)
		(property "MPN" "CR0402-FX-1000GLF"
			(at 239.85 -52.25 0)
			(layer "B.Fab")
			(hide yes)
			(effects
				(font
					(size 1 1)
					(thickness 0.15)
				)
				(justify mirror)
			)
		)
		(property "Manufacturer" "Bourns"
			(at 239.85 -52.25 0)
			(layer "B.Fab")
			(hide yes)
			(effects
				(font
					(size 1 1)
					(thickness 0.15)
				)
				(justify mirror)
			)
		)
		(property "Tolerance" "1%"
			(at 239.85 -52.25 0)
			(layer "B.Fab")
			(hide yes)
			(effects
				(font
					(size 1 1)
					(thickness 0.15)
				)
				(justify mirror)
			)
		)
		(property "Val" "100R"
			(at 239.85 -52.25 0)
			(layer "B.Fab")
			(hide yes)
			(effects
				(font
					(size 1 1)
					(thickness 0.15)
				)
				(justify mirror)
			)
		)
		(sheetfile "lpddr5-testbed.kicad_sch")
		(attr smd exclude_from_pos_files exclude_from_bom dnp)
		(fp_rect
			(start -0.93 0.47)
			(end 0.93 -0.47)
			(stroke
				(width 0.05)
				(type solid)
			)
			(fill no)
			(layer "B.CrtYd")
		)
		(fp_rect
			(start -0.5 0.25)
			(end 0.5 -0.25)
			(stroke
				(width 0.15)
				(type solid)
			)
			(fill no)
			(layer "B.Fab")
		)
		(pad "1" smd roundrect
			(at -0.485 0 90)
			(size 0.59 0.64)
			(layers "B.Cu" "B.Mask" "B.Paste")
			(roundrect_rratio 0.25)
			(net 14 "GND")
			(pintype "passive")
		)
		(pad "2" smd roundrect
			(at 0.485 0 90)
			(size 0.59 0.64)
			(layers "B.Cu" "B.Mask" "B.Paste")
			(roundrect_rratio 0.25)
			(net 40 "/LPDDR5/~{RESET}")
			(pintype "passive")
		)
	)
	(footprint "antmicro-footprints:C_0402_1005Metric"
		(layer "B.Cu")
		(at 136.175 84.35 -90)
		(descr "Capacitor SMD 0402")
		(tags "capacitor SMD 0402")
		(property "Reference" "C52"
			(at 0.85 -0.325 90)
			(unlocked yes)
			(layer "B.SilkS")
			(effects
				(font
					(size 0.7 0.7)
					(thickness 0.15)
				)
				(justify left bottom mirror)
			)
		)
		(property "Value" "C_4u7_0402"
			(at -1.022927 -2.155213 90)
			(layer "B.Fab")
			(effects
				(font
					(size 0.7 0.7)
					(thickness 0.15)
				)
				(justify left bottom mirror)
			)
		)
		(property "Author" "Antmicro"
			(at 51.825 220.525 0)
			(layer "B.Fab")
			(hide yes)
			(effects
				(font
					(size 1 1)
					(thickness 0.15)
				)
				(justify mirror)
			)
		)
		(property "Dielectric" ""
			(at 51.825 220.525 0)
			(layer "B.Fab")
			(hide yes)
			(effects
				(font
					(size 1 1)
					(thickness 0.15)
				)
				(justify mirror)
			)
		)
		(property "License" "Apache-2.0"
			(at 51.825 220.525 0)
			(layer "B.Fab")
			(hide yes)
			(effects
				(font
					(size 1 1)
					(thickness 0.15)
				)
				(justify mirror)
			)
		)
		(property "MPN" "GRM155R61A475MEAAD"
			(at 51.825 220.525 0)
			(layer "B.Fab")
			(hide yes)
			(effects
				(font
					(size 1 1)
					(thickness 0.15)
				)
				(justify mirror)
			)
		)
		(property "Manufacturer" "Murata"
			(at 51.825 220.525 0)
			(layer "B.Fab")
			(hide yes)
			(effects
				(font
					(size 1 1)
					(thickness 0.15)
				)
				(justify mirror)
			)
		)
		(property "Val" "4u7"
			(at 51.825 220.525 0)
			(layer "B.Fab")
			(hide yes)
			(effects
				(font
					(size 1 1)
					(thickness 0.15)
				)
				(justify mirror)
			)
		)
		(property "Voltage" ""
			(at 51.825 220.525 0)
			(layer "B.Fab")
			(hide yes)
			(effects
				(font
					(size 1 1)
					(thickness 0.15)
				)
				(justify mirror)
			)
		)
		(sheetname "LPDDR5")
		(sheetfile "lpddr5.kicad_sch")
		(attr smd)
		(fp_rect
			(start -0.9659 0.481258)
			(end 0.9649 -0.458742)
			(stroke
				(width 0.05)
				(type solid)
			)
			(fill no)
			(layer "B.CrtYd")
		)
		(fp_line
			(start -0.499 0.25)
			(end 0.499 0.25)
			(stroke
				(width 0.15)
				(type solid)
			)
			(layer "B.Fab")
		)
		(fp_line
			(start 0.499 0.25)
			(end 0.499 -0.248)
			(stroke
				(width 0.15)
				(type solid)
			)
			(layer "B.Fab")
		)
		(fp_line
			(start -0.499 -0.248)
			(end -0.499 0.25)
			(stroke
				(width 0.15)
				(type solid)
			)
			(layer "B.Fab")
		)
		(fp_line
			(start 0.499 -0.248)
			(end -0.499 -0.248)
			(stroke
				(width 0.15)
				(type solid)
			)
			(layer "B.Fab")
		)
		(pad "1" smd roundrect
			(at -0.484 0 270)
			(size 0.59 0.64)
			(layers "B.Cu" "B.Mask" "B.Paste")
			(roundrect_rratio 0.25)
			(net 14 "GND")
			(pintype "passive")
		)
		(pad "2" smd roundrect
			(at 0.484 0 270)
			(size 0.59 0.64)
			(layers "B.Cu" "B.Mask" "B.Paste")
			(roundrect_rratio 0.25)
			(net 12 "+0V9")
			(pintype "passive")
		)
	)
	(footprint "antmicro-footprints:C_0402_1005Metric"
		(layer "B.Cu")
		(at 140.375 86.15)
		(descr "Capacitor SMD 0402")
		(tags "capacitor SMD 0402")
		(property "Reference" "C44"
			(at 0.925 0.55 0)
			(unlocked yes)
			(layer "B.SilkS")
			(effects
				(font
					(size 0.7 0.7)
					(thickness 0.15)
				)
				(justify right bottom mirror)
			)
		)
		(property "Value" "C_4u7_0402"
			(at -1.022927 -2.155213 0)
			(layer "B.Fab")
			(effects
				(font
					(size 0.7 0.7)
					(thickness 0.15)
				)
				(justify right bottom mirror)
			)
		)
		(property "Author" "Antmicro"
			(at 0 0 0)
			(layer "B.Fab")
			(hide yes)
			(effects
				(font
					(size 1 1)
					(thickness 0.15)
				)
				(justify mirror)
			)
		)
		(property "Dielectric" ""
			(at 0 0 0)
			(layer "B.Fab")
			(hide yes)
			(effects
				(font
					(size 1 1)
					(thickness 0.15)
				)
				(justify mirror)
			)
		)
		(property "License" "Apache-2.0"
			(at 0 0 0)
			(layer "B.Fab")
			(hide yes)
			(effects
				(font
					(size 1 1)
					(thickness 0.15)
				)
				(justify mirror)
			)
		)
		(property "MPN" "GRM155R61A475MEAAD"
			(at 0 0 0)
			(layer "B.Fab")
			(hide yes)
			(effects
				(font
					(size 1 1)
					(thickness 0.15)
				)
				(justify mirror)
			)
		)
		(property "Manufacturer" "Murata"
			(at 0 0 0)
			(layer "B.Fab")
			(hide yes)
			(effects
				(font
					(size 1 1)
					(thickness 0.15)
				)
				(justify mirror)
			)
		)
		(property "Val" "4u7"
			(at 0 0 0)
			(layer "B.Fab")
			(hide yes)
			(effects
				(font
					(size 1 1)
					(thickness 0.15)
				)
				(justify mirror)
			)
		)
		(property "Voltage" ""
			(at 0 0 0)
			(layer "B.Fab")
			(hide yes)
			(effects
				(font
					(size 1 1)
					(thickness 0.15)
				)
				(justify mirror)
			)
		)
		(sheetname "LPDDR5")
		(sheetfile "lpddr5.kicad_sch")
		(attr smd)
		(fp_rect
			(start -0.9659 0.481258)
			(end 0.9649 -0.458742)
			(stroke
				(width 0.05)
				(type solid)
			)
			(fill no)
			(layer "B.CrtYd")
		)
		(fp_line
			(start -0.499 -0.248)
			(end -0.499 0.25)
			(stroke
				(width 0.15)
				(type solid)
			)
			(layer "B.Fab")
		)
		(fp_line
			(start -0.499 0.25)
			(end 0.499 0.25)
			(stroke
				(width 0.15)
				(type solid)
			)
			(layer "B.Fab")
		)
		(fp_line
			(start 0.499 -0.248)
			(end -0.499 -0.248)
			(stroke
				(width 0.15)
				(type solid)
			)
			(layer "B.Fab")
		)
		(fp_line
			(start 0.499 0.25)
			(end 0.499 -0.248)
			(stroke
				(width 0.15)
				(type solid)
			)
			(layer "B.Fab")
		)
		(pad "1" smd roundrect
			(at -0.484 0)
			(size 0.59 0.64)
			(layers "B.Cu" "B.Mask" "B.Paste")
			(roundrect_rratio 0.25)
			(net 14 "GND")
			(pintype "passive")
		)
		(pad "2" smd roundrect
			(at 0.484 0)
			(size 0.59 0.64)
			(layers "B.Cu" "B.Mask" "B.Paste")
			(roundrect_rratio 0.25)
			(net 35 "+1V8")
			(pintype "passive")
		)
	)
)
